(kicad_pcb
	(version 20241229)
	(generator "pcbnew")
	(generator_version "9.0")
	(general
		(thickness 1.711)
		(legacy_teardrops no)
	)
	(paper "A4")
	(title_block
		(title "Antmicro Baseboard for Jetson AGX Thor")
		(date "2026-02-18")
		(rev "1.1.0")
		(company "Antmicro Ltd")
		(comment 1 "www.antmicro.com")
		(comment 9 "footprints 85-88 of 1170")
	)
	(layers
		(0 "F.Cu" signal)
		(4 "In1.Cu" signal)
		(6 "In2.Cu" signal)
		(8 "In3.Cu" signal)
		(10 "In4.Cu" jumper)
		(12 "In5.Cu" signal)
		(14 "In6.Cu" signal)
		(16 "In7.Cu" signal)
		(18 "In8.Cu" signal)
		(2 "B.Cu" signal)
		(9 "F.Adhes" user "F.Adhesive")
		(11 "B.Adhes" user "B.Adhesive")
		(13 "F.Paste" user)
		(15 "B.Paste" user)
		(5 "F.SilkS" user "F.Silkscreen")
		(7 "B.SilkS" user "B.Silkscreen")
		(1 "F.Mask" user)
		(3 "B.Mask" user)
		(17 "Dwgs.User" user "User.Drawings")
		(19 "Cmts.User" user "User.Comments")
		(21 "Eco1.User" user "User.Eco1")
		(23 "Eco2.User" user "User.Eco2")
		(25 "Edge.Cuts" user)
		(27 "Margin" user)
		(31 "F.CrtYd" user "F.Courtyard")
		(29 "B.CrtYd" user "B.Courtyard")
		(35 "F.Fab" user)
		(33 "B.Fab" user)
	)
	(footprint "antmicro-footprints:C_0805_2012Metric"
		(layer "F.Cu")
		(at 164.054468 93.31 -90)
		(descr "Capacitor SMD 0805")
		(tags "capacitor SMD 0805")
		(property "Reference" "C260"
			(at -4.71 0.454468 90)
			(layer "F.SilkS")
			(effects
				(font
					(size 0.7 0.7)
					(thickness 0.15)
				)
				(justify right top)
			)
		)
		(property "Value" "C_22u_25V_0805"
			(at -2.055717 1.963152 90)
			(layer "F.Fab")
			(effects
				(font
					(size 0.7 0.7)
					(thickness 0.15)
				)
				(justify right top)
			)
		)
		(property "Datasheet" "https://product.samsungsem.com/mlcc/CL21A226MAYNNN.do"
			(at 0 0 90)
			(layer "F.Fab")
			(hide yes)
			(effects
				(font
					(size 1.27 1.27)
					(thickness 0.15)
				)
			)
		)
		(property "Description" "SMT Multilayer Ceramic Capacitor, 22uF, +/-20%, 25V, X5R, 0805 [2012 Metric]"
			(at 0 0 90)
			(layer "F.Fab")
			(hide yes)
			(effects
				(font
					(size 1.27 1.27)
					(thickness 0.15)
				)
			)
		)
		(property "MPN" "CL21A226MAYNNNE"
			(at 0 0 270)
			(unlocked yes)
			(layer "F.Fab")
			(hide yes)
			(effects
				(font
					(size 1 1)
					(thickness 0.15)
				)
			)
		)
		(property "Manufacturer" "Samsung Electro-Mechanics"
			(at 0 0 270)
			(unlocked yes)
			(layer "F.Fab")
			(hide yes)
			(effects
				(font
					(size 1 1)
					(thickness 0.15)
				)
			)
		)
		(property "License" "Apache-2.0"
			(at 0 0 270)
			(unlocked yes)
			(layer "F.Fab")
			(hide yes)
			(effects
				(font
					(size 1 1)
					(thickness 0.15)
				)
			)
		)
		(property "Author" "Antmicro"
			(at 0 0 270)
			(unlocked yes)
			(layer "F.Fab")
			(hide yes)
			(effects
				(font
					(size 1 1)
					(thickness 0.15)
				)
			)
		)
		(property "Val" "22u"
			(at 0 0 270)
			(unlocked yes)
			(layer "F.Fab")
			(hide yes)
			(effects
				(font
					(size 1 1)
					(thickness 0.15)
				)
			)
		)
		(property "Voltage" "25V"
			(at 0 0 270)
			(unlocked yes)
			(layer "F.Fab")
			(hide yes)
			(effects
				(font
					(size 1 1)
					(thickness 0.15)
				)
			)
		)
		(property "Dielectric" "X5R"
			(at 0 0 270)
			(unlocked yes)
			(layer "F.Fab")
			(hide yes)
			(effects
				(font
					(size 1 1)
					(thickness 0.15)
				)
			)
		)
		(property "Public" "False"
			(at 0 0 270)
			(unlocked yes)
			(layer "F.Fab")
			(hide yes)
			(effects
				(font
					(size 1 1)
					(thickness 0.15)
				)
			)
		)
		(component_classes
			(class "DCDC_SOM")
		)
		(sheetname "/DCDC/")
		(sheetfile "dcdc.kicad_sch")
		(attr smd)
		(fp_line
			(start -0.3 0.7)
			(end 0.3 0.7)
			(stroke
				(width 0.15)
				(type solid)
			)
			(layer "F.SilkS")
		)
		(fp_line
			(start -0.3 -0.7)
			(end 0.3 -0.7)
			(stroke
				(width 0.15)
				(type solid)
			)
			(layer "F.SilkS")
		)
		(fp_rect
			(start 1.95 -0.9)
			(end -1.95 0.9)
			(stroke
				(width 0.05)
				(type default)
			)
			(fill no)
			(layer "F.CrtYd")
		)
		(fp_rect
			(start -0.95 -0.675)
			(end 0.95 0.675)
			(stroke
				(width 0.15)
				(type solid)
			)
			(fill no)
			(layer "F.Fab")
		)
		(fp_text user "${REFERENCE}"
			(at -1.9 3.947 90)
			(layer "F.Fab")
			(effects
				(font
					(size 0.7 0.7)
					(thickness 0.15)
				)
				(justify right top)
			)
		)
		(fp_text user "License: Apache-2.0"
			(at -1.9 4.947 90)
			(layer "F.Fab")
			(effects
				(font
					(size 0.7 0.7)
					(thickness 0.15)
				)
				(justify right top)
			)
		)
		(fp_text user "Author: Antmicro"
			(at -1.9 5.947 90)
			(layer "F.Fab")
			(effects
				(font
					(size 0.7 0.7)
					(thickness 0.15)
				)
				(justify right top)
			)
		)
		(pad "1" smd roundrect
			(at -1.1 0 270)
			(size 1.2 1.3)
			(layers "F.Cu" "F.Mask" "F.Paste")
			(roundrect_rratio 0.25)
			(net 1 "GND")
			(pintype "passive")
		)
		(pad "2" smd roundrect
			(at 1.1 0 270)
			(size 1.2 1.3)
			(layers "F.Cu" "F.Mask" "F.Paste")
			(roundrect_rratio 0.25)
			(net 903 "/DCDC/16V_OUT")
			(pintype "passive")
		)
	)
	(footprint "antmicro-footprints:LED_0603_1608Metric_Y"
		(layer "F.Cu")
		(at 190.686 149.7 180)
		(descr "LED SMD 0603 Yellow")
		(tags "LED SMD 0603 Yellow")
		(property "Reference" "D30"
			(at -0.84 -0.9 0)
			(layer "F.SilkS")
			(effects
				(font
					(size 0.7 0.7)
					(thickness 0.15)
				)
				(justify right top)
			)
		)
		(property "Value" "LED_Y_0603_LTST-C191KSKT"
			(at 0 1.6 0)
			(layer "F.Fab")
			(effects
				(font
					(size 0.7 0.7)
					(thickness 0.15)
				)
				(justify right top)
			)
		)
		(property "Datasheet" "https://optoelectronics.liteon.com/upload/download/DS22-2000-224/LTST-C191KSKT.PDF"
			(at 0 0 0)
			(layer "F.Fab")
			(hide yes)
			(effects
				(font
					(size 1.27 1.27)
					(thickness 0.15)
				)
			)
		)
		(property "Description" "LED, Yellow, SMD, 0603, 30 mA, 2.1 V, 588 nm"
			(at 0 0 0)
			(layer "F.Fab")
			(hide yes)
			(effects
				(font
					(size 1.27 1.27)
					(thickness 0.15)
				)
			)
		)
		(property "MPN" "LTST-C191KSKT"
			(at 0 0 180)
			(unlocked yes)
			(layer "F.Fab")
			(hide yes)
			(effects
				(font
					(size 1 1)
					(thickness 0.15)
				)
			)
		)
		(property "Manufacturer" "Lite-On"
			(at 0 0 180)
			(unlocked yes)
			(layer "F.Fab")
			(hide yes)
			(effects
				(font
					(size 1 1)
					(thickness 0.15)
				)
			)
		)
		(property "Color" "Yellow"
			(at 0 0 180)
			(unlocked yes)
			(layer "F.Fab")
			(hide yes)
			(effects
				(font
					(size 1 1)
					(thickness 0.15)
				)
			)
		)
		(property "Author" "Antmicro"
			(at 0 0 180)
			(unlocked yes)
			(layer "F.Fab")
			(hide yes)
			(effects
				(font
					(size 1 1)
					(thickness 0.15)
				)
			)
		)
		(property "License" "Apache-2.0"
			(at 0 0 180)
			(unlocked yes)
			(layer "F.Fab")
			(hide yes)
			(effects
				(font
					(size 1 1)
					(thickness 0.15)
				)
			)
		)
		(sheetname "/SFP/")
		(sheetfile "sfp.kicad_sch")
		(attr smd)
		(fp_line
			(start 0.22 0.35)
			(end -0.22 0.35)
			(stroke
				(width 0.15)
				(type solid)
			)
			(layer "F.SilkS")
		)
		(fp_line
			(start 0.22 -0.35)
			(end -0.22 -0.35)
			(stroke
				(width 0.15)
				(type solid)
			)
			(layer "F.SilkS")
		)
		(fp_line
			(start 0.105328 0.201008)
			(end 0.105329 -0.198992)
			(stroke
				(width 0.1)
				(type solid)
			)
			(layer "F.SilkS")
		)
		(fp_line
			(start 0.105328 0.201008)
			(end -0.094672 0.001008)
			(stroke
				(width 0.1)
				(type solid)
			)
			(layer "F.SilkS")
		)
		(fp_line
			(start 0.105328 0.001008)
			(end 0.240001 0.001)
			(stroke
				(width 0.1)
				(type solid)
			)
			(layer "F.SilkS")
		)
		(fp_line
			(start -0.094672 0.201008)
			(end -0.094672 -0.198992)
			(stroke
				(width 0.1)
				(type solid)
			)
			(layer "F.SilkS")
		)
		(fp_line
			(start -0.094672 0.001008)
			(end 0.105329 -0.198992)
			(stroke
				(width 0.1)
				(type solid)
			)
			(layer "F.SilkS")
		)
		(fp_line
			(start -0.094672 0.001008)
			(end -0.24 0.001008)
			(stroke
				(width 0.1)
				(type solid)
			)
			(layer "F.SilkS")
		)
		(fp_line
			(start -1.18 -0.319)
			(end -1.18 0.321)
			(stroke
				(width 0.15)
				(type solid)
			)
			(layer "F.SilkS")
		)
		(fp_poly
			(pts
				(xy 1.25 0.65) (xy -1.25 0.65) (xy -1.25 -0.65) (xy 1.25 -0.65)
			)
			(stroke
				(width 0.05)
				(type solid)
			)
			(fill no)
			(layer "F.CrtYd")
		)
		(fp_line
			(start 0.599 0)
			(end 0.200999 0)
			(stroke
				(width 0.15)
				(type solid)
			)
			(layer "F.Fab")
		)
		(fp_line
			(start 0.201 0.2)
			(end 0.200999 0)
			(stroke
				(width 0.15)
				(type solid)
			)
			(layer "F.Fab")
		)
		(fp_line
			(start 0.201 -0.202)
			(end -0.101 0)
			(stroke
				(width 0.15)
				(type solid)
			)
			(layer "F.Fab")
		)
		(fp_line
			(start 0.200999 0)
			(end 0.201 -0.202)
			(stroke
				(width 0.15)
				(type solid)
			)
			(layer "F.Fab")
		)
		(fp_line
			(start -0.101 0)
			(end 0.201 0.2)
			(stroke
				(width 0.15)
				(type solid)
			)
			(layer "F.Fab")
		)
		(fp_line
			(start -0.199 0.2)
			(end -0.199 0.1)
			(stroke
				(width 0.15)
				(type solid)
			)
			(layer "F.Fab")
		)
		(fp_line
			(start -0.199 0)
			(end -0.597 0)
			(stroke
				(width 0.15)
				(type solid)
			)
			(layer "F.Fab")
		)
		(fp_line
			(start -0.199 -0.202)
			(end -0.199 0.1)
			(stroke
				(width 0.15)
				(type solid)
			)
			(layer "F.Fab")
		)
		(fp_poly
			(pts
				(xy 0.848 0.4) (xy -0.85 0.4) (xy -0.85 -0.402) (xy 0.848 -0.401999)
			)
			(stroke
				(width 0.15)
				(type solid)
			)
			(fill no)
			(layer "F.Fab")
		)
		(fp_text user "Author: Antmicro"
			(at -1.31 4.769 0)
			(layer "F.Fab")
			(effects
				(font
					(size 0.7 0.7)
					(thickness 0.15)
				)
				(justify right top)
			)
		)
		(fp_text user "License: Apache-2.0"
			(at -1.31 5.769 0)
			(layer "F.Fab")
			(effects
				(font
					(size 0.7 0.7)
					(thickness 0.15)
				)
				(justify right top)
			)
		)
		(fp_text user "${REFERENCE}"
			(at -1.309999 3.769 0)
			(layer "F.Fab")
			(effects
				(font
					(size 0.7 0.7)
					(thickness 0.15)
				)
				(justify right top)
			)
		)
		(pad "1" smd roundrect
			(at -0.7 0)
			(size 0.8 1)
			(layers "F.Cu" "F.Mask" "F.Paste")
			(roundrect_rratio 0.2)
			(net 543 "Net-(D30-C)")
			(pinfunction "C")
			(pintype "passive")
		)
		(pad "2" smd roundrect
			(at 0.7 0)
			(size 0.8 1)
			(layers "F.Cu" "F.Mask" "F.Paste")
			(roundrect_rratio 0.2)
			(net 2 "+3V3")
			(pinfunction "A")
			(pintype "passive")
		)
	)
	(footprint "antmicro-footprints:C_0805_2012Metric"
		(layer "F.Cu")
		(at 171.38 99.81 90)
		(descr "Capacitor SMD 0805")
		(tags "capacitor SMD 0805")
		(property "Reference" "C257"
			(at -4.595 0.345 90)
			(layer "F.SilkS")
			(effects
				(font
					(size 0.7 0.7)
					(thickness 0.15)
				)
				(justify left bottom)
			)
		)
		(property "Value" "C_22u_25V_0805"
			(at -2.055717 1.963152 90)
			(layer "F.Fab")
			(effects
				(font
					(size 0.7 0.7)
					(thickness 0.15)
				)
				(justify left bottom)
			)
		)
		(property "Datasheet" "https://product.samsungsem.com/mlcc/CL21A226MAYNNN.do"
			(at 0 0 90)
			(layer "F.Fab")
			(hide yes)
			(effects
				(font
					(size 1.27 1.27)
					(thickness 0.15)
				)
			)
		)
		(property "Description" "SMT Multilayer Ceramic Capacitor, 22uF, +/-20%, 25V, X5R, 0805 [2012 Metric]"
			(at 0 0 90)
			(layer "F.Fab")
			(hide yes)
			(effects
				(font
					(size 1.27 1.27)
					(thickness 0.15)
				)
			)
		)
		(property "MPN" "CL21A226MAYNNNE"
			(at 0 0 90)
			(unlocked yes)
			(layer "F.Fab")
			(hide yes)
			(effects
				(font
					(size 1 1)
					(thickness 0.15)
				)
			)
		)
		(property "Manufacturer" "Samsung Electro-Mechanics"
			(at 0 0 90)
			(unlocked yes)
			(layer "F.Fab")
			(hide yes)
			(effects
				(font
					(size 1 1)
					(thickness 0.15)
				)
			)
		)
		(property "License" "Apache-2.0"
			(at 0 0 90)
			(unlocked yes)
			(layer "F.Fab")
			(hide yes)
			(effects
				(font
					(size 1 1)
					(thickness 0.15)
				)
			)
		)
		(property "Author" "Antmicro"
			(at 0 0 90)
			(unlocked yes)
			(layer "F.Fab")
			(hide yes)
			(effects
				(font
					(size 1 1)
					(thickness 0.15)
				)
			)
		)
		(property "Val" "22u"
			(at 0 0 90)
			(unlocked yes)
			(layer "F.Fab")
			(hide yes)
			(effects
				(font
					(size 1 1)
					(thickness 0.15)
				)
			)
		)
		(property "Voltage" "25V"
			(at 0 0 90)
			(unlocked yes)
			(layer "F.Fab")
			(hide yes)
			(effects
				(font
					(size 1 1)
					(thickness 0.15)
				)
			)
		)
		(property "Dielectric" "X5R"
			(at 0 0 90)
			(unlocked yes)
			(layer "F.Fab")
			(hide yes)
			(effects
				(font
					(size 1 1)
					(thickness 0.15)
				)
			)
		)
		(property "Public" "False"
			(at 0 0 90)
			(unlocked yes)
			(layer "F.Fab")
			(hide yes)
			(effects
				(font
					(size 1 1)
					(thickness 0.15)
				)
			)
		)
		(component_classes
			(class "DCDC_SOM")
		)
		(sheetname "/DCDC/")
		(sheetfile "dcdc.kicad_sch")
		(attr smd)
		(fp_line
			(start -0.3 -0.7)
			(end 0.3 -0.7)
			(stroke
				(width 0.15)
				(type solid)
			)
			(layer "F.SilkS")
		)
		(fp_line
			(start -0.3 0.7)
			(end 0.3 0.7)
			(stroke
				(width 0.15)
				(type solid)
			)
			(layer "F.SilkS")
		)
		(fp_rect
			(start 1.95 -0.9)
			(end -1.95 0.9)
			(stroke
				(width 0.05)
				(type default)
			)
			(fill no)
			(layer "F.CrtYd")
		)
		(fp_rect
			(start -0.95 -0.675)
			(end 0.95 0.675)
			(stroke
				(width 0.15)
				(type solid)
			)
			(fill no)
			(layer "F.Fab")
		)
		(fp_text user "Author: Antmicro"
			(at -1.9 5.947 90)
			(layer "F.Fab")
			(effects
				(font
					(size 0.7 0.7)
					(thickness 0.15)
				)
				(justify left bottom)
			)
		)
		(fp_text user "${REFERENCE}"
			(at -1.9 3.947 90)
			(layer "F.Fab")
			(effects
				(font
					(size 0.7 0.7)
					(thickness 0.15)
				)
				(justify left bottom)
			)
		)
		(fp_text user "License: Apache-2.0"
			(at -1.9 4.947 90)
			(layer "F.Fab")
			(effects
				(font
					(size 0.7 0.7)
					(thickness 0.15)
				)
				(justify left bottom)
			)
		)
		(pad "1" smd roundrect
			(at -1.1 0 90)
			(size 1.2 1.3)
			(layers "F.Cu" "F.Mask" "F.Paste")
			(roundrect_rratio 0.25)
			(net 1 "GND")
			(pintype "passive")
		)
		(pad "2" smd roundrect
			(at 1.1 0 90)
			(size 1.2 1.3)
			(layers "F.Cu" "F.Mask" "F.Paste")
			(roundrect_rratio 0.25)
			(net 903 "/DCDC/16V_OUT")
			(pintype "passive")
		)
	)
	(footprint "antmicro-footprints:C_0805_2012Metric"
		(layer "F.Cu")
		(at 171.34 93.32 -90)
		(descr "Capacitor SMD 0805")
		(tags "capacitor SMD 0805")
		(property "Reference" "C249"
			(at 1.745 0.425 90)
			(layer "F.SilkS")
			(effects
				(font
					(size 0.7 0.7)
					(thickness 0.15)
				)
				(justify right top)
			)
		)
		(property "Value" "C_22u_25V_0805"
			(at -2.055717 1.963152 90)
			(layer "F.Fab")
			(effects
				(font
					(size 0.7 0.7)
					(thickness 0.15)
				)
				(justify right top)
			)
		)
		(property "Datasheet" "https://product.samsungsem.com/mlcc/CL21A226MAYNNN.do"
			(at 0 0 90)
			(layer "F.Fab")
			(hide yes)
			(effects
				(font
					(size 1.27 1.27)
					(thickness 0.15)
				)
			)
		)
		(property "Description" "SMT Multilayer Ceramic Capacitor, 22uF, +/-20%, 25V, X5R, 0805 [2012 Metric]"
			(at 0 0 90)
			(layer "F.Fab")
			(hide yes)
			(effects
				(font
					(size 1.27 1.27)
					(thickness 0.15)
				)
			)
		)
		(property "MPN" "CL21A226MAYNNNE"
			(at 0 0 270)
			(unlocked yes)
			(layer "F.Fab")
			(hide yes)
			(effects
				(font
					(size 1 1)
					(thickness 0.15)
				)
			)
		)
		(property "Manufacturer" "Samsung Electro-Mechanics"
			(at 0 0 270)
			(unlocked yes)
			(layer "F.Fab")
			(hide yes)
			(effects
				(font
					(size 1 1)
					(thickness 0.15)
				)
			)
		)
		(property "License" "Apache-2.0"
			(at 0 0 270)
			(unlocked yes)
			(layer "F.Fab")
			(hide yes)
			(effects
				(font
					(size 1 1)
					(thickness 0.15)
				)
			)
		)
		(property "Author" "Antmicro"
			(at 0 0 270)
			(unlocked yes)
			(layer "F.Fab")
			(hide yes)
			(effects
				(font
					(size 1 1)
					(thickness 0.15)
				)
			)
		)
		(property "Val" "22u"
			(at 0 0 270)
			(unlocked yes)
			(layer "F.Fab")
			(hide yes)
			(effects
				(font
					(size 1 1)
					(thickness 0.15)
				)
			)
		)
		(property "Voltage" "25V"
			(at 0 0 270)
			(unlocked yes)
			(layer "F.Fab")
			(hide yes)
			(effects
				(font
					(size 1 1)
					(thickness 0.15)
				)
			)
		)
		(property "Dielectric" "X5R"
			(at 0 0 270)
			(unlocked yes)
			(layer "F.Fab")
			(hide yes)
			(effects
				(font
					(size 1 1)
					(thickness 0.15)
				)
			)
		)
		(property "Public" "False"
			(at 0 0 270)
			(unlocked yes)
			(layer "F.Fab")
			(hide yes)
			(effects
				(font
					(size 1 1)
					(thickness 0.15)
				)
			)
		)
		(component_classes
			(class "DCDC_SOM")
		)
		(sheetname "/DCDC/")
		(sheetfile "dcdc.kicad_sch")
		(attr smd)
		(fp_line
			(start -0.3 0.7)
			(end 0.3 0.7)
			(stroke
				(width 0.15)
				(type solid)
			)
			(layer "F.SilkS")
		)
		(fp_line
			(start -0.3 -0.7)
			(end 0.3 -0.7)
			(stroke
				(width 0.15)
				(type solid)
			)
			(layer "F.SilkS")
		)
		(fp_rect
			(start 1.95 -0.9)
			(end -1.95 0.9)
			(stroke
				(width 0.05)
				(type default)
			)
			(fill no)
			(layer "F.CrtYd")
		)
		(fp_rect
			(start -0.95 -0.675)
			(end 0.95 0.675)
			(stroke
				(width 0.15)
				(type solid)
			)
			(fill no)
			(layer "F.Fab")
		)
		(fp_text user "${REFERENCE}"
			(at -1.9 3.947 90)
			(layer "F.Fab")
			(effects
				(font
					(size 0.7 0.7)
					(thickness 0.15)
				)
				(justify right top)
			)
		)
		(fp_text user "License: Apache-2.0"
			(at -1.9 4.947 90)
			(layer "F.Fab")
			(effects
				(font
					(size 0.7 0.7)
					(thickness 0.15)
				)
				(justify right top)
			)
		)
		(fp_text user "Author: Antmicro"
			(at -1.9 5.947 90)
			(layer "F.Fab")
			(effects
				(font
					(size 0.7 0.7)
					(thickness 0.15)
				)
				(justify right top)
			)
		)
		(pad "1" smd roundrect
			(at -1.1 0 270)
			(size 1.2 1.3)
			(layers "F.Cu" "F.Mask" "F.Paste")
			(roundrect_rratio 0.25)
			(net 1 "GND")
			(pintype "passive")
		)
		(pad "2" smd roundrect
			(at 1.1 0 270)
			(size 1.2 1.3)
			(layers "F.Cu" "F.Mask" "F.Paste")
			(roundrect_rratio 0.25)
			(net 903 "/DCDC/16V_OUT")
			(pintype "passive")
		)
	)
)
